(kicad_pcb
	(version 20260206)
	(generator "pcbnew")
	(generator_version "10.0")
	(general
		(thickness 1.6)
		(legacy_teardrops no)
	)
	(paper "A4")
	(title_block
		(title "03242023_DA0F0TMBIJ0_F0T_Motherboard_J_brd_V01_OCP.brd")
		(comment 1 "Grand Teton / footprints 4610-4615 of 6105")
	)
	(layers
		(0 "F.Cu" signal "TOP")
		(4 "In1.Cu" signal "GND")
		(6 "In2.Cu" signal "IN1")
		(8 "In3.Cu" signal "GND1")
		(10 "In4.Cu" signal "IN2")
		(12 "In5.Cu" signal "GND2")
		(14 "In6.Cu" signal "IN3")
		(16 "In7.Cu" signal "GND3")
		(18 "In8.Cu" signal "VCC")
		(20 "In9.Cu" signal "VCC1")
		(22 "In10.Cu" signal "GND4")
		(24 "In11.Cu" signal "IN4")
		(26 "In12.Cu" signal "GND5")
		(28 "In13.Cu" signal "IN5")
		(30 "In14.Cu" signal "GND6")
		(32 "In15.Cu" signal "IN6")
		(34 "In16.Cu" signal "GND7")
		(2 "B.Cu" signal "BOTTOM")
		(9 "F.Adhes" user "F.Adhesive")
		(11 "B.Adhes" user "B.Adhesive")
		(13 "F.Paste" user "Package Geometry/Pastemask Top")
		(15 "B.Paste" user "Package Geometry/Pastemask Bottom")
		(5 "F.SilkS" user "Ref Des/Silkscreen Top")
		(7 "B.SilkS" user "Ref Des/Silkscreen Bottom")
		(1 "F.Mask" user "Board Geometry/Soldermask Top")
		(3 "B.Mask" user "Board Geometry/Soldermask Bottom")
		(17 "Dwgs.User" user "User.Drawings")
		(19 "Cmts.User" user "User.Comments")
		(21 "Eco1.User" user "User.Eco1")
		(23 "Eco2.User" user "User.Eco2")
		(25 "Edge.Cuts" user "Board Geometry/Outline")
		(27 "Margin" user)
		(31 "F.CrtYd" user "Package Geometry/Place Bound Top")
		(29 "B.CrtYd" user "Package Geometry/Place Bound Bottom")
		(35 "F.Fab" user "Ref Des/Assembly Top")
		(33 "B.Fab" user "Ref Des/Assembly Bottom")
	)
	(footprint ""
		(layer "B.Cu")
		(at 327.15708 -68.339208 90)
		(property "Reference" "L2"
			(at 0 0 90)
			(layer "B.SilkS")
			(hide yes)
			(effects
				(font
					(size 1.27 1.27)
				)
				(justify mirror)
			)
		)
		(property "Value" ""
			(at 0 0 90)
			(layer "B.Fab")
			(effects
				(font
					(size 1.27 1.27)
				)
				(justify mirror)
			)
		)
		(duplicate_pad_numbers_are_jumpers no)
		(fp_line
			(start 0.762 -0.381)
			(end -0.762 -0.381)
			(stroke
				(width 0.1524)
				(type default)
			)
			(layer "B.SilkS")
		)
		(fp_line
			(start -0.762 -0.381)
			(end -0.762 0.381)
			(stroke
				(width 0.1524)
				(type default)
			)
			(layer "B.SilkS")
		)
		(fp_line
			(start 0.762 0.381)
			(end 0.762 -0.381)
			(stroke
				(width 0.1524)
				(type default)
			)
			(layer "B.SilkS")
		)
		(fp_line
			(start -0.762 0.381)
			(end 0.762 0.381)
			(stroke
				(width 0.1524)
				(type default)
			)
			(layer "B.SilkS")
		)
		(fp_line
			(start 0.681736 -0.307086)
			(end 0.118364 -0.307086)
			(stroke
				(width 0.1)
				(type default)
			)
			(layer "B.Fab")
		)
		(fp_line
			(start 0.118364 -0.307086)
			(end 0.118364 -0.2794)
			(stroke
				(width 0.1)
				(type default)
			)
			(layer "B.Fab")
		)
		(fp_line
			(start -0.118872 -0.306324)
			(end -0.680466 -0.306324)
			(stroke
				(width 0.1)
				(type default)
			)
			(layer "B.Fab")
		)
		(fp_line
			(start -0.680466 -0.306324)
			(end -0.680466 0.306324)
			(stroke
				(width 0.1)
				(type default)
			)
			(layer "B.Fab")
		)
		(fp_line
			(start 0.118364 -0.2794)
			(end -0.118872 -0.2794)
			(stroke
				(width 0.1)
				(type default)
			)
			(layer "B.Fab")
		)
		(fp_line
			(start -0.118872 -0.2794)
			(end -0.118872 -0.306324)
			(stroke
				(width 0.1)
				(type default)
			)
			(layer "B.Fab")
		)
		(fp_line
			(start 0.119634 0.2794)
			(end 0.119634 0.30607)
			(stroke
				(width 0.1)
				(type default)
			)
			(layer "B.Fab")
		)
		(fp_line
			(start -0.118364 0.2794)
			(end 0.119634 0.2794)
			(stroke
				(width 0.1)
				(type default)
			)
			(layer "B.Fab")
		)
		(fp_line
			(start 0.681736 0.30607)
			(end 0.681736 -0.307086)
			(stroke
				(width 0.1)
				(type default)
			)
			(layer "B.Fab")
		)
		(fp_line
			(start 0.119634 0.30607)
			(end 0.681736 0.30607)
			(stroke
				(width 0.1)
				(type default)
			)
			(layer "B.Fab")
		)
		(fp_line
			(start -0.118364 0.306324)
			(end -0.118364 0.2794)
			(stroke
				(width 0.1)
				(type default)
			)
			(layer "B.Fab")
		)
		(fp_line
			(start -0.680466 0.306324)
			(end -0.118364 0.306324)
			(stroke
				(width 0.1)
				(type default)
			)
			(layer "B.Fab")
		)
		(pad "1" smd rect
			(at 0.40005 0 90)
			(size 0.4572 0.508)
			(layers "B.Cu" "B.Mask" "B.Paste")
			(net "P1V05_PCH_AUX")
		)
		(pad "2" smd rect
			(at -0.40005 0 90)
			(size 0.4572 0.508)
			(layers "B.Cu" "B.Mask" "B.Paste")
			(net "P1V05_PCH_PLL_AUX")
		)
	)
	(footprint ""
		(layer "B.Cu")
		(at 369.49888 -44.160948 180)
		(property "Reference" "R4116"
			(at 0 0 0)
			(layer "B.SilkS")
			(hide yes)
			(effects
				(font
					(size 1.27 1.27)
				)
				(justify mirror)
			)
		)
		(property "Value" ""
			(at 0 0 0)
			(layer "B.Fab")
			(effects
				(font
					(size 1.27 1.27)
				)
				(justify mirror)
			)
		)
		(duplicate_pad_numbers_are_jumpers no)
		(fp_line
			(start 0.7874 0.4064)
			(end 0.7874 -0.4064)
			(stroke
				(width 0.1524)
				(type default)
			)
			(layer "B.SilkS")
		)
		(fp_line
			(start 0.7874 -0.4064)
			(end -0.7874 -0.4064)
			(stroke
				(width 0.1524)
				(type default)
			)
			(layer "B.SilkS")
		)
		(fp_line
			(start -0.7874 0.4064)
			(end 0.7874 0.4064)
			(stroke
				(width 0.1524)
				(type default)
			)
			(layer "B.SilkS")
		)
		(fp_line
			(start -0.7874 -0.4064)
			(end -0.7874 0.4064)
			(stroke
				(width 0.1524)
				(type default)
			)
			(layer "B.SilkS")
		)
		(fp_line
			(start 0.67945 0.3048)
			(end 0.67945 -0.305054)
			(stroke
				(width 0.1)
				(type default)
			)
			(layer "B.Fab")
		)
		(fp_line
			(start 0.67945 -0.305054)
			(end 0.12065 -0.305054)
			(stroke
				(width 0.1)
				(type default)
			)
			(layer "B.Fab")
		)
		(fp_line
			(start 0.12065 0.3048)
			(end 0.67945 0.3048)
			(stroke
				(width 0.1)
				(type default)
			)
			(layer "B.Fab")
		)
		(fp_line
			(start 0.12065 0.2794)
			(end 0.12065 0.3048)
			(stroke
				(width 0.1)
				(type default)
			)
			(layer "B.Fab")
		)
		(fp_line
			(start 0.12065 -0.2794)
			(end -0.12065 -0.2794)
			(stroke
				(width 0.1)
				(type default)
			)
			(layer "B.Fab")
		)
		(fp_line
			(start 0.12065 -0.305054)
			(end 0.12065 -0.2794)
			(stroke
				(width 0.1)
				(type default)
			)
			(layer "B.Fab")
		)
		(fp_line
			(start -0.120396 0.3048)
			(end -0.120396 0.2794)
			(stroke
				(width 0.1)
				(type default)
			)
			(layer "B.Fab")
		)
		(fp_line
			(start -0.120396 0.2794)
			(end 0.12065 0.2794)
			(stroke
				(width 0.1)
				(type default)
			)
			(layer "B.Fab")
		)
		(fp_line
			(start -0.12065 -0.2794)
			(end -0.12065 -0.3048)
			(stroke
				(width 0.1)
				(type default)
			)
			(layer "B.Fab")
		)
		(fp_line
			(start -0.12065 -0.3048)
			(end -0.67945 -0.3048)
			(stroke
				(width 0.1)
				(type default)
			)
			(layer "B.Fab")
		)
		(fp_line
			(start -0.67945 0.3048)
			(end -0.120396 0.3048)
			(stroke
				(width 0.1)
				(type default)
			)
			(layer "B.Fab")
		)
		(fp_line
			(start -0.67945 -0.3048)
			(end -0.67945 0.3048)
			(stroke
				(width 0.1)
				(type default)
			)
			(layer "B.Fab")
		)
		(pad "1" smd circle
			(at 0.40005 0)
			(size 0 0)
			(layers "B.Cu" "B.Mask" "B.Paste")
			(net "PD_PCH_GPP_E_8")
		)
		(pad "2" smd circle
			(at -0.40005 0)
			(size 0 0)
			(layers "B.Cu" "B.Mask" "B.Paste")
			(net "GND")
		)
	)
	(footprint ""
		(layer "B.Cu")
		(at 286.268414 -319.263776 180)
		(property "Reference" "C8"
			(at 0 0 0)
			(layer "B.SilkS")
			(hide yes)
			(effects
				(font
					(size 1.27 1.27)
				)
				(justify mirror)
			)
		)
		(property "Value" ""
			(at 0 0 0)
			(layer "B.Fab")
			(effects
				(font
					(size 1.27 1.27)
				)
				(justify mirror)
			)
		)
		(duplicate_pad_numbers_are_jumpers no)
		(fp_line
			(start 0.7874 0.4064)
			(end 0.7874 -0.4064)
			(stroke
				(width 0.1524)
				(type default)
			)
			(layer "B.SilkS")
		)
		(fp_line
			(start 0.7874 -0.4064)
			(end -0.7874 -0.4064)
			(stroke
				(width 0.1524)
				(type default)
			)
			(layer "B.SilkS")
		)
		(fp_line
			(start -0.7874 0.4064)
			(end 0.7874 0.4064)
			(stroke
				(width 0.1524)
				(type default)
			)
			(layer "B.SilkS")
		)
		(fp_line
			(start -0.7874 -0.4064)
			(end -0.7874 0.4064)
			(stroke
				(width 0.1524)
				(type default)
			)
			(layer "B.SilkS")
		)
		(fp_line
			(start 0.67945 0.3048)
			(end 0.67945 -0.305054)
			(stroke
				(width 0.1)
				(type default)
			)
			(layer "B.Fab")
		)
		(fp_line
			(start 0.67945 -0.305054)
			(end 0.12065 -0.305054)
			(stroke
				(width 0.1)
				(type default)
			)
			(layer "B.Fab")
		)
		(fp_line
			(start 0.12065 0.3048)
			(end 0.67945 0.3048)
			(stroke
				(width 0.1)
				(type default)
			)
			(layer "B.Fab")
		)
		(fp_line
			(start 0.12065 0.2794)
			(end 0.12065 0.3048)
			(stroke
				(width 0.1)
				(type default)
			)
			(layer "B.Fab")
		)
		(fp_line
			(start 0.12065 -0.2794)
			(end -0.12065 -0.2794)
			(stroke
				(width 0.1)
				(type default)
			)
			(layer "B.Fab")
		)
		(fp_line
			(start 0.12065 -0.305054)
			(end 0.12065 -0.2794)
			(stroke
				(width 0.1)
				(type default)
			)
			(layer "B.Fab")
		)
		(fp_line
			(start -0.120396 0.3048)
			(end -0.120396 0.2794)
			(stroke
				(width 0.1)
				(type default)
			)
			(layer "B.Fab")
		)
		(fp_line
			(start -0.120396 0.2794)
			(end 0.12065 0.2794)
			(stroke
				(width 0.1)
				(type default)
			)
			(layer "B.Fab")
		)
		(fp_line
			(start -0.12065 -0.2794)
			(end -0.12065 -0.3048)
			(stroke
				(width 0.1)
				(type default)
			)
			(layer "B.Fab")
		)
		(fp_line
			(start -0.12065 -0.3048)
			(end -0.67945 -0.3048)
			(stroke
				(width 0.1)
				(type default)
			)
			(layer "B.Fab")
		)
		(fp_line
			(start -0.67945 0.3048)
			(end -0.120396 0.3048)
			(stroke
				(width 0.1)
				(type default)
			)
			(layer "B.Fab")
		)
		(fp_line
			(start -0.67945 -0.3048)
			(end -0.67945 0.3048)
			(stroke
				(width 0.1)
				(type default)
			)
			(layer "B.Fab")
		)
		(pad "1" smd circle
			(at 0.40005 0)
			(size 0 0)
			(layers "B.Cu" "B.Mask" "B.Paste")
			(net "P3V3_AUX")
		)
		(pad "2" smd circle
			(at -0.40005 0)
			(size 0 0)
			(layers "B.Cu" "B.Mask" "B.Paste")
			(net "GND")
		)
	)
	(footprint ""
		(layer "B.Cu")
		(at 193.38036 -120.614948)
		(property "Reference" "R1205"
			(at 0 0 0)
			(layer "B.SilkS")
			(hide yes)
			(effects
				(font
					(size 1.27 1.27)
				)
				(justify mirror)
			)
		)
		(property "Value" ""
			(at 0 0 0)
			(layer "B.Fab")
			(effects
				(font
					(size 1.27 1.27)
				)
				(justify mirror)
			)
		)
		(duplicate_pad_numbers_are_jumpers no)
		(fp_line
			(start -0.7874 -0.4064)
			(end -0.7874 0.4064)
			(stroke
				(width 0.1524)
				(type default)
			)
			(layer "B.SilkS")
		)
		(fp_line
			(start -0.7874 0.4064)
			(end 0.7874 0.4064)
			(stroke
				(width 0.1524)
				(type default)
			)
			(layer "B.SilkS")
		)
		(fp_line
			(start 0.7874 -0.4064)
			(end -0.7874 -0.4064)
			(stroke
				(width 0.1524)
				(type default)
			)
			(layer "B.SilkS")
		)
		(fp_line
			(start 0.7874 0.4064)
			(end 0.7874 -0.4064)
			(stroke
				(width 0.1524)
				(type default)
			)
			(layer "B.SilkS")
		)
		(fp_line
			(start -0.67945 -0.3048)
			(end -0.67945 0.3048)
			(stroke
				(width 0.1)
				(type default)
			)
			(layer "B.Fab")
		)
		(fp_line
			(start -0.67945 0.3048)
			(end -0.120396 0.3048)
			(stroke
				(width 0.1)
				(type default)
			)
			(layer "B.Fab")
		)
		(fp_line
			(start -0.12065 -0.3048)
			(end -0.67945 -0.3048)
			(stroke
				(width 0.1)
				(type default)
			)
			(layer "B.Fab")
		)
		(fp_line
			(start -0.12065 -0.2794)
			(end -0.12065 -0.3048)
			(stroke
				(width 0.1)
				(type default)
			)
			(layer "B.Fab")
		)
		(fp_line
			(start -0.120396 0.2794)
			(end 0.12065 0.2794)
			(stroke
				(width 0.1)
				(type default)
			)
			(layer "B.Fab")
		)
		(fp_line
			(start -0.120396 0.3048)
			(end -0.120396 0.2794)
			(stroke
				(width 0.1)
				(type default)
			)
			(layer "B.Fab")
		)
		(fp_line
			(start 0.12065 -0.305054)
			(end 0.12065 -0.2794)
			(stroke
				(width 0.1)
				(type default)
			)
			(layer "B.Fab")
		)
		(fp_line
			(start 0.12065 -0.2794)
			(end -0.12065 -0.2794)
			(stroke
				(width 0.1)
				(type default)
			)
			(layer "B.Fab")
		)
		(fp_line
			(start 0.12065 0.2794)
			(end 0.12065 0.3048)
			(stroke
				(width 0.1)
				(type default)
			)
			(layer "B.Fab")
		)
		(fp_line
			(start 0.12065 0.3048)
			(end 0.67945 0.3048)
			(stroke
				(width 0.1)
				(type default)
			)
			(layer "B.Fab")
		)
		(fp_line
			(start 0.67945 -0.305054)
			(end 0.12065 -0.305054)
			(stroke
				(width 0.1)
				(type default)
			)
			(layer "B.Fab")
		)
		(fp_line
			(start 0.67945 0.3048)
			(end 0.67945 -0.305054)
			(stroke
				(width 0.1)
				(type default)
			)
			(layer "B.Fab")
		)
		(pad "1" smd circle
			(at 0.40005 0 180)
			(size 0 0)
			(layers "B.Cu" "B.Mask" "B.Paste")
			(net "RST_PLTRST_N")
		)
		(pad "2" smd circle
			(at -0.40005 0 180)
			(size 0 0)
			(layers "B.Cu" "B.Mask" "B.Paste")
			(net "RST_PLTRST_PLD_N")
		)
	)
	(footprint ""
		(layer "B.Cu")
		(at 353.924108 -237.709202 -90)
		(property "Reference" "C1405"
			(at 0 0 90)
			(layer "B.SilkS")
			(hide yes)
			(effects
				(font
					(size 1.27 1.27)
				)
				(justify mirror)
			)
		)
		(property "Value" ""
			(at 0 0 90)
			(layer "B.Fab")
			(effects
				(font
					(size 1.27 1.27)
				)
				(justify mirror)
			)
		)
		(duplicate_pad_numbers_are_jumpers no)
		(fp_line
			(start -1.2954 0.5842)
			(end 1.2954 0.5842)
			(stroke
				(width 0.1524)
				(type default)
			)
			(layer "B.SilkS")
		)
		(fp_line
			(start 1.2954 0.5842)
			(end 1.2954 -0.5842)
			(stroke
				(width 0.1524)
				(type default)
			)
			(layer "B.SilkS")
		)
		(fp_line
			(start -1.2954 -0.5842)
			(end -1.2954 0.5842)
			(stroke
				(width 0.1524)
				(type default)
			)
			(layer "B.SilkS")
		)
		(fp_line
			(start 0 -0.5842)
			(end 0 0.5842)
			(stroke
				(width 0.1524)
				(type default)
			)
			(layer "B.SilkS")
		)
		(fp_line
			(start 1.2954 -0.5842)
			(end -1.2954 -0.5842)
			(stroke
				(width 0.1524)
				(type default)
			)
			(layer "B.SilkS")
		)
		(fp_line
			(start -0.8636 0.4572)
			(end 0.8636 0.4572)
			(stroke
				(width 0.1)
				(type default)
			)
			(layer "B.Fab")
		)
		(fp_line
			(start 0.8636 0.4572)
			(end 0.8636 0.4064)
			(stroke
				(width 0.1)
				(type default)
			)
			(layer "B.Fab")
		)
		(fp_line
			(start -1.1938 0.4064)
			(end -0.8636 0.4064)
			(stroke
				(width 0.1)
				(type default)
			)
			(layer "B.Fab")
		)
		(fp_line
			(start -0.8636 0.4064)
			(end -0.8636 0.4572)
			(stroke
				(width 0.1)
				(type default)
			)
			(layer "B.Fab")
		)
		(fp_line
			(start 0.8636 0.4064)
			(end 1.1938 0.4064)
			(stroke
				(width 0.1)
				(type default)
			)
			(layer "B.Fab")
		)
		(fp_line
			(start 1.1938 0.4064)
			(end 1.1938 -0.4064)
			(stroke
				(width 0.1)
				(type default)
			)
			(layer "B.Fab")
		)
		(fp_line
			(start -1.1938 -0.4064)
			(end -1.1938 0.4064)
			(stroke
				(width 0.1)
				(type default)
			)
			(layer "B.Fab")
		)
		(fp_line
			(start -0.8636 -0.4064)
			(end -1.1938 -0.4064)
			(stroke
				(width 0.1)
				(type default)
			)
			(layer "B.Fab")
		)
		(fp_line
			(start 0.8636 -0.4064)
			(end 0.8636 -0.4572)
			(stroke
				(width 0.1)
				(type default)
			)
			(layer "B.Fab")
		)
		(fp_line
			(start 1.1938 -0.4064)
			(end 0.8636 -0.4064)
			(stroke
				(width 0.1)
				(type default)
			)
			(layer "B.Fab")
		)
		(fp_line
			(start -0.8636 -0.4572)
			(end -0.8636 -0.4064)
			(stroke
				(width 0.1)
				(type default)
			)
			(layer "B.Fab")
		)
		(fp_line
			(start 0.8636 -0.4572)
			(end -0.8636 -0.4572)
			(stroke
				(width 0.1)
				(type default)
			)
			(layer "B.Fab")
		)
		(pad "1" smd rect
			(at 0.7366 0 180)
			(size 0.7112 0.8128)
			(layers "B.Cu" "B.Mask" "B.Paste")
			(net "PVNN_MAIN_CPU0")
		)
		(pad "2" smd rect
			(at -0.7366 0 180)
			(size 0.7112 0.8128)
			(layers "B.Cu" "B.Mask" "B.Paste")
			(net "GND")
		)
	)
	(footprint ""
		(layer "B.Cu")
		(at 160.83788 -116.296948)
		(property "Reference" "R4267"
			(at 0 0 0)
			(layer "B.SilkS")
			(hide yes)
			(effects
				(font
					(size 1.27 1.27)
				)
				(justify mirror)
			)
		)
		(property "Value" ""
			(at 0 0 0)
			(layer "B.Fab")
			(effects
				(font
					(size 1.27 1.27)
				)
				(justify mirror)
			)
		)
		(duplicate_pad_numbers_are_jumpers no)
		(fp_line
			(start -0.7874 -0.4064)
			(end -0.7874 0.4064)
			(stroke
				(width 0.1524)
				(type default)
			)
			(layer "B.SilkS")
		)
		(fp_line
			(start -0.7874 0.4064)
			(end 0.7874 0.4064)
			(stroke
				(width 0.1524)
				(type default)
			)
			(layer "B.SilkS")
		)
		(fp_line
			(start 0.7874 -0.4064)
			(end -0.7874 -0.4064)
			(stroke
				(width 0.1524)
				(type default)
			)
			(layer "B.SilkS")
		)
		(fp_line
			(start 0.7874 0.4064)
			(end 0.7874 -0.4064)
			(stroke
				(width 0.1524)
				(type default)
			)
			(layer "B.SilkS")
		)
		(fp_line
			(start -0.67945 -0.3048)
			(end -0.67945 0.3048)
			(stroke
				(width 0.1)
				(type default)
			)
			(layer "B.Fab")
		)
		(fp_line
			(start -0.67945 0.3048)
			(end -0.120396 0.3048)
			(stroke
				(width 0.1)
				(type default)
			)
			(layer "B.Fab")
		)
		(fp_line
			(start -0.12065 -0.3048)
			(end -0.67945 -0.3048)
			(stroke
				(width 0.1)
				(type default)
			)
			(layer "B.Fab")
		)
		(fp_line
			(start -0.12065 -0.2794)
			(end -0.12065 -0.3048)
			(stroke
				(width 0.1)
				(type default)
			)
			(layer "B.Fab")
		)
		(fp_line
			(start -0.120396 0.2794)
			(end 0.12065 0.2794)
			(stroke
				(width 0.1)
				(type default)
			)
			(layer "B.Fab")
		)
		(fp_line
			(start -0.120396 0.3048)
			(end -0.120396 0.2794)
			(stroke
				(width 0.1)
				(type default)
			)
			(layer "B.Fab")
		)
		(fp_line
			(start 0.12065 -0.305054)
			(end 0.12065 -0.2794)
			(stroke
				(width 0.1)
				(type default)
			)
			(layer "B.Fab")
		)
		(fp_line
			(start 0.12065 -0.2794)
			(end -0.12065 -0.2794)
			(stroke
				(width 0.1)
				(type default)
			)
			(layer "B.Fab")
		)
		(fp_line
			(start 0.12065 0.2794)
			(end 0.12065 0.3048)
			(stroke
				(width 0.1)
				(type default)
			)
			(layer "B.Fab")
		)
		(fp_line
			(start 0.12065 0.3048)
			(end 0.67945 0.3048)
			(stroke
				(width 0.1)
				(type default)
			)
			(layer "B.Fab")
		)
		(fp_line
			(start 0.67945 -0.305054)
			(end 0.12065 -0.305054)
			(stroke
				(width 0.1)
				(type default)
			)
			(layer "B.Fab")
		)
		(fp_line
			(start 0.67945 0.3048)
			(end 0.67945 -0.305054)
			(stroke
				(width 0.1)
				(type default)
			)
			(layer "B.Fab")
		)
		(pad "1" smd circle
			(at 0.40005 0 180)
			(size 0 0)
			(layers "B.Cu" "B.Mask" "B.Paste")
			(net "PWRGD_P3V3_AUX")
		)
		(pad "2" smd circle
			(at -0.40005 0 180)
			(size 0 0)
			(layers "B.Cu" "B.Mask" "B.Paste")
			(net "PWRGD_P3V3_AUX_PDB")
		)
	)
)
